# BASEBOARD_FAB2 (Tioga Pass) — schematic netlist excerpt (pin names and nets, part order shuffled) for the footprints in the layout excerpt that follows; sources: Cadence DE-HDL packaged netlist, KiCad conversion of Wiwynn_Tioga_Pass_MB.brd

R12W10  665KR2B-GP  0.1%  pkg SMD-RG2  page 197 : \1\ = VR_PVDDQ_DEF_AIINSEN ; \2\ = VR_PVDDQ_DEF_VINSEN
R7B9  RES  0.0 5% CHIP  pkg 0402  page 232 : A = FM_PVPP_CPU0_EN ; B = FM_PVPP_PVDDQ_CPU0_EN_DEF

(kicad_pcb
	(version 20260206)
	(generator "pcbnew")
	(generator_version "10.0")
	(general
		(thickness 1.6)
		(legacy_teardrops no)
	)
	(paper "A4")
	(title_block
		(title "Wiwynn_Tioga_Pass_MB.brd")
		(comment 1 "Tioga Pass / footprints 1862-1863 of 4770")
	)
	(layers
		(0 "F.Cu" signal "TOP")
		(4 "In1.Cu" signal "L2GND")
		(6 "In2.Cu" signal "L3")
		(8 "In3.Cu" signal "L4GND")
		(10 "In4.Cu" signal "L5")
		(12 "In5.Cu" signal "L6GND")
		(14 "In6.Cu" signal "L7VCC")
		(16 "In7.Cu" signal "L8VCC")
		(18 "In8.Cu" signal "L9GND")
		(20 "In9.Cu" signal "L10")
		(22 "In10.Cu" signal "L11GND")
		(24 "In11.Cu" signal "L12")
		(26 "In12.Cu" signal "L13GND")
		(2 "B.Cu" signal "BOTTOM")
		(9 "F.Adhes" user "F.Adhesive")
		(11 "B.Adhes" user "B.Adhesive")
		(13 "F.Paste" user "Package Geometry/Pastemask Top")
		(15 "B.Paste" user "Package Geometry/Pastemask Bottom")
		(5 "F.SilkS" user "Ref Des/Silkscreen Top")
		(7 "B.SilkS" user "Ref Des/Silkscreen Bottom")
		(1 "F.Mask" user "Board Geometry/Soldermask Top")
		(3 "B.Mask" user "Board Geometry/Soldermask Bottom")
		(17 "Dwgs.User" user "User.Drawings")
		(19 "Cmts.User" user "User.Comments")
		(21 "Eco1.User" user "User.Eco1")
		(23 "Eco2.User" user "User.Eco2")
		(25 "Edge.Cuts" user "Board Geometry/Outline")
		(27 "Margin" user)
		(31 "F.CrtYd" user "Package Geometry/Place Bound Top")
		(29 "B.CrtYd" user "Package Geometry/Place Bound Bottom")
		(35 "F.Fab" user "Ref Des/Assembly Top")
		(33 "B.Fab" user "Ref Des/Assembly Bottom")
	)
	(footprint ""
		(layer "F.Cu")
		(at 354.244656 -137.833608 180)
		(property "Reference" "R12W10"
			(at 0 0 180)
			(layer "F.SilkS")
			(hide yes)
			(effects
				(font
					(size 1.27 1.27)
				)
			)
		)
		(property "Value" "*"
			(at 0.064008 -4.108196 180)
			(unlocked yes)
			(layer "F.Fab")
			(hide yes)
			(effects
				(font
					(size 1.27 1.016)
					(thickness 0.1524)
				)
			)
		)
		(property "Device Type" "665KR2B-GP_SMD-RG2-665KR2B-GP,A"
			(at 0.064008 -5.632196 180)
			(unlocked yes)
			(layer "F.Fab")
			(hide yes)
			(effects
				(font
					(size 1.27 1.016)
					(thickness 0.1524)
				)
			)
		)
		(duplicate_pad_numbers_are_jumpers no)
		(fp_line
			(start 0.508 -0.9398)
			(end -0.508 -0.9398)
			(stroke
				(width 0.1524)
				(type default)
			)
			(layer "F.SilkS")
		)
		(fp_line
			(start -0.508 -0.9398)
			(end -0.508 0.9398)
			(stroke
				(width 0.1524)
				(type default)
			)
			(layer "F.SilkS")
		)
		(fp_rect
			(start -0.508 0.9398)
			(end 0.508 -0.9398)
			(stroke
				(width 0)
				(type default)
			)
			(fill no)
			(layer "F.CrtYd")
		)
		(fp_rect
			(start -0.508 0.9398)
			(end 0.508 -0.9398)
			(stroke
				(width 0)
				(type default)
			)
			(fill no)
			(layer "F.Fab")
		)
		(pad "1" smd custom
			(at 0 -0.4445 180)
			(size 0.1397 0.1397)
			(layers "F.Cu" "F.Mask" "F.Paste")
			(net "VR_PVDDQ_DEF_AIINSEN")
			(options
				(clearance outline)
				(anchor circle)
			)
			(primitives
				(gr_poly
					(pts
						(arc
							(start -0.1778 -0.2794)
							(mid -0.249642 -0.249642)
							(end -0.2794 -0.1778)
						)
						(arc
							(start -0.2794 0.1778)
							(mid -0.249642 0.249642)
							(end -0.1778 0.2794)
						)
						(arc
							(start 0.1778 0.2794)
							(mid 0.249642 0.249642)
							(end 0.2794 0.1778)
						)
						(arc
							(start 0.2794 -0.1778)
							(mid 0.249642 -0.249642)
							(end 0.1778 -0.2794)
						)
					)
					(width 0)
					(fill yes)
				)
			)
		)
		(pad "2" smd custom
			(at 0 0.4445 180)
			(size 0.1397 0.1397)
			(layers "F.Cu" "F.Mask" "F.Paste")
			(net "VR_PVDDQ_DEF_VINSEN")
			(options
				(clearance outline)
				(anchor circle)
			)
			(primitives
				(gr_poly
					(pts
						(arc
							(start -0.1778 -0.2794)
							(mid -0.249642 -0.249642)
							(end -0.2794 -0.1778)
						)
						(arc
							(start -0.2794 0.1778)
							(mid -0.249642 0.249642)
							(end -0.1778 0.2794)
						)
						(arc
							(start 0.1778 0.2794)
							(mid 0.249642 0.249642)
							(end 0.2794 0.1778)
						)
						(arc
							(start 0.2794 -0.1778)
							(mid 0.249642 -0.249642)
							(end 0.1778 -0.2794)
						)
					)
					(width 0)
					(fill yes)
				)
			)
		)
	)
	(footprint ""
		(layer "F.Cu")
		(at 339.092032 -129.587498 90)
		(property "Reference" "R7B9"
			(at 0 0 90)
			(layer "F.SilkS")
			(hide yes)
			(effects
				(font
					(size 1.27 1.27)
				)
			)
		)
		(property "Value" ""
			(at 0 0 90)
			(layer "F.Fab")
			(effects
				(font
					(size 1.27 1.27)
				)
			)
		)
		(duplicate_pad_numbers_are_jumpers no)
		(fp_poly
			(pts
				(xy -0.2794 -0.1016) (xy 0.2794 -0.1016) (xy 0.2794 0.9906) (xy -0.2794 0.9906)
			)
			(stroke
				(width 0)
				(type default)
			)
			(fill no)
			(layer "F.CrtYd")
		)
		(fp_line
			(start 0.2794 -0.1016)
			(end -0.2794 -0.1016)
			(stroke
				(width 0.1)
				(type default)
			)
			(layer "F.Fab")
		)
		(fp_line
			(start -0.2794 -0.1016)
			(end -0.2794 0.9906)
			(stroke
				(width 0.1)
				(type default)
			)
			(layer "F.Fab")
		)
		(fp_line
			(start 0.2794 0.9906)
			(end 0.2794 -0.1016)
			(stroke
				(width 0.1)
				(type default)
			)
			(layer "F.Fab")
		)
		(fp_line
			(start -0.2794 0.9906)
			(end 0.2794 0.9906)
			(stroke
				(width 0.1)
				(type default)
			)
			(layer "F.Fab")
		)
		(pad "1" smd rect
			(at 0 0 90)
			(size 0.508 0.508)
			(layers "F.Cu" "F.Mask" "F.Paste")
			(net "FM_PVPP_CPU0_EN")
		)
		(pad "2" smd rect
			(at 0 0.889 90)
			(size 0.508 0.508)
			(layers "F.Cu" "F.Mask" "F.Paste")
			(net "FM_PVPP_PVDDQ_CPU0_EN_DEF")
		)
		(zone
			(layer "F.Cu")
			(hatch none 0.5)
			(connect_pads
				(clearance 0)
			)
			(min_thickness 0.25)
			(keepout
				(tracks allowed)
				(vias not_allowed)
				(pads allowed)
				(copperpour not_allowed)
				(footprints allowed)
			)
			(placement
				(enabled no)
				(sheetname "")
			)
			(fill
				(thermal_gap 0.5)
				(thermal_bridge_width 0.5)
				(island_removal_mode 0)
			)
			(polygon
				(pts
					(xy 339.346032 -129.333498) (xy 339.346032 -129.841498) (xy 339.727032 -129.841498) (xy 339.727032 -129.333498)
				)
			)
		)
		(zone
			(layer "F.Cu")
			(hatch none 0.5)
			(connect_pads
				(clearance 0)
			)
			(min_thickness 0.25)
			(keepout
				(tracks not_allowed)
				(vias allowed)
				(pads allowed)
				(copperpour not_allowed)
				(footprints allowed)
			)
			(placement
				(enabled no)
				(sheetname "")
			)
			(fill
				(thermal_gap 0.5)
				(thermal_bridge_width 0.5)
				(island_removal_mode 0)
			)
			(polygon
				(pts
					(xy 339.727032 -129.333498) (xy 339.727032 -129.841498) (xy 339.346032 -129.841498) (xy 339.346032 -129.333498)
				)
			)
		)
	)
)
